(kicad_pcb
	(version 20260206)
	(generator "pcbnew")
	(generator_version "10.0")
	(general
		(thickness 1.6)
		(legacy_teardrops no)
	)
	(paper "A4")
	(title_block
		(title "03242023_DA0F0TMBIJ0_F0T_Motherboard_J_brd_V01_OCP.brd")
		(comment 1 "Grand Teton / footprints 3838-3844 of 6105")
	)
	(layers
		(0 "F.Cu" signal "TOP")
		(4 "In1.Cu" signal "GND")
		(6 "In2.Cu" signal "IN1")
		(8 "In3.Cu" signal "GND1")
		(10 "In4.Cu" signal "IN2")
		(12 "In5.Cu" signal "GND2")
		(14 "In6.Cu" signal "IN3")
		(16 "In7.Cu" signal "GND3")
		(18 "In8.Cu" signal "VCC")
		(20 "In9.Cu" signal "VCC1")
		(22 "In10.Cu" signal "GND4")
		(24 "In11.Cu" signal "IN4")
		(26 "In12.Cu" signal "GND5")
		(28 "In13.Cu" signal "IN5")
		(30 "In14.Cu" signal "GND6")
		(32 "In15.Cu" signal "IN6")
		(34 "In16.Cu" signal "GND7")
		(2 "B.Cu" signal "BOTTOM")
		(9 "F.Adhes" user "F.Adhesive")
		(11 "B.Adhes" user "B.Adhesive")
		(13 "F.Paste" user "Package Geometry/Pastemask Top")
		(15 "B.Paste" user "Package Geometry/Pastemask Bottom")
		(5 "F.SilkS" user "Ref Des/Silkscreen Top")
		(7 "B.SilkS" user "Ref Des/Silkscreen Bottom")
		(1 "F.Mask" user "Board Geometry/Soldermask Top")
		(3 "B.Mask" user "Board Geometry/Soldermask Bottom")
		(17 "Dwgs.User" user "User.Drawings")
		(19 "Cmts.User" user "User.Comments")
		(21 "Eco1.User" user "User.Eco1")
		(23 "Eco2.User" user "User.Eco2")
		(25 "Edge.Cuts" user "Board Geometry/Outline")
		(27 "Margin" user)
		(31 "F.CrtYd" user "Package Geometry/Place Bound Top")
		(29 "B.CrtYd" user "Package Geometry/Place Bound Bottom")
		(35 "F.Fab" user "Ref Des/Assembly Top")
		(33 "B.Fab" user "Ref Des/Assembly Bottom")
	)
	(footprint ""
		(layer "F.Cu")
		(at 348.506796 -333.804514 -90)
		(property "Reference" "PC299_P0_1"
			(at 0 0 270)
			(layer "F.SilkS")
			(hide yes)
			(effects
				(font
					(size 1.27 1.27)
				)
			)
		)
		(property "Value" ""
			(at 0 0 270)
			(layer "F.Fab")
			(effects
				(font
					(size 1.27 1.27)
				)
			)
		)
		(duplicate_pad_numbers_are_jumpers no)
		(fp_line
			(start -0.7874 0.4064)
			(end -0.7874 -0.4064)
			(stroke
				(width 0.1524)
				(type default)
			)
			(layer "F.SilkS")
		)
		(fp_line
			(start 0.7874 0.4064)
			(end -0.7874 0.4064)
			(stroke
				(width 0.1524)
				(type default)
			)
			(layer "F.SilkS")
		)
		(fp_line
			(start -0.7874 -0.4064)
			(end 0.7874 -0.4064)
			(stroke
				(width 0.1524)
				(type default)
			)
			(layer "F.SilkS")
		)
		(fp_line
			(start 0.7874 -0.4064)
			(end 0.7874 0.4064)
			(stroke
				(width 0.1524)
				(type default)
			)
			(layer "F.SilkS")
		)
		(fp_line
			(start -0.67945 0.3048)
			(end -0.67945 -0.305054)
			(stroke
				(width 0.1)
				(type default)
			)
			(layer "F.Fab")
		)
		(fp_line
			(start -0.12065 0.3048)
			(end -0.67945 0.3048)
			(stroke
				(width 0.1)
				(type default)
			)
			(layer "F.Fab")
		)
		(fp_line
			(start 0.120396 0.3048)
			(end 0.120396 0.2794)
			(stroke
				(width 0.1)
				(type default)
			)
			(layer "F.Fab")
		)
		(fp_line
			(start 0.67945 0.3048)
			(end 0.120396 0.3048)
			(stroke
				(width 0.1)
				(type default)
			)
			(layer "F.Fab")
		)
		(fp_line
			(start -0.12065 0.2794)
			(end -0.12065 0.3048)
			(stroke
				(width 0.1)
				(type default)
			)
			(layer "F.Fab")
		)
		(fp_line
			(start 0.120396 0.2794)
			(end -0.12065 0.2794)
			(stroke
				(width 0.1)
				(type default)
			)
			(layer "F.Fab")
		)
		(fp_line
			(start -0.12065 -0.2794)
			(end 0.12065 -0.2794)
			(stroke
				(width 0.1)
				(type default)
			)
			(layer "F.Fab")
		)
		(fp_line
			(start 0.12065 -0.2794)
			(end 0.12065 -0.3048)
			(stroke
				(width 0.1)
				(type default)
			)
			(layer "F.Fab")
		)
		(fp_line
			(start 0.12065 -0.3048)
			(end 0.67945 -0.3048)
			(stroke
				(width 0.1)
				(type default)
			)
			(layer "F.Fab")
		)
		(fp_line
			(start 0.67945 -0.3048)
			(end 0.67945 0.3048)
			(stroke
				(width 0.1)
				(type default)
			)
			(layer "F.Fab")
		)
		(fp_line
			(start -0.67945 -0.305054)
			(end -0.12065 -0.305054)
			(stroke
				(width 0.1)
				(type default)
			)
			(layer "F.Fab")
		)
		(fp_line
			(start -0.12065 -0.305054)
			(end -0.12065 -0.2794)
			(stroke
				(width 0.1)
				(type default)
			)
			(layer "F.Fab")
		)
		(pad "1" smd circle
			(at -0.40005 0 270)
			(size 0 0)
			(layers "F.Cu" "F.Mask" "F.Paste")
			(net "SW_P12V_PVCCIN_CPU0_FLT")
		)
		(pad "2" smd circle
			(at 0.40005 0 270)
			(size 0 0)
			(layers "F.Cu" "F.Mask" "F.Paste")
			(net "GND")
		)
	)
	(footprint ""
		(layer "F.Cu")
		(at 117.526816 -258.72694 90)
		(property "Reference" "C306"
			(at 0 0 90)
			(layer "F.SilkS")
			(hide yes)
			(effects
				(font
					(size 1.27 1.27)
				)
			)
		)
		(property "Value" ""
			(at 0 0 90)
			(layer "F.Fab")
			(effects
				(font
					(size 1.27 1.27)
				)
			)
		)
		(duplicate_pad_numbers_are_jumpers no)
		(fp_line
			(start 0.7874 -0.4064)
			(end 0.7874 0.4064)
			(stroke
				(width 0.1524)
				(type default)
			)
			(layer "F.SilkS")
		)
		(fp_line
			(start -0.7874 -0.4064)
			(end 0.7874 -0.4064)
			(stroke
				(width 0.1524)
				(type default)
			)
			(layer "F.SilkS")
		)
		(fp_line
			(start 0.7874 0.4064)
			(end -0.7874 0.4064)
			(stroke
				(width 0.1524)
				(type default)
			)
			(layer "F.SilkS")
		)
		(fp_line
			(start -0.7874 0.4064)
			(end -0.7874 -0.4064)
			(stroke
				(width 0.1524)
				(type default)
			)
			(layer "F.SilkS")
		)
		(fp_line
			(start -0.12065 -0.305054)
			(end -0.12065 -0.2794)
			(stroke
				(width 0.1)
				(type default)
			)
			(layer "F.Fab")
		)
		(fp_line
			(start -0.67945 -0.305054)
			(end -0.12065 -0.305054)
			(stroke
				(width 0.1)
				(type default)
			)
			(layer "F.Fab")
		)
		(fp_line
			(start 0.67945 -0.3048)
			(end 0.67945 0.3048)
			(stroke
				(width 0.1)
				(type default)
			)
			(layer "F.Fab")
		)
		(fp_line
			(start 0.12065 -0.3048)
			(end 0.67945 -0.3048)
			(stroke
				(width 0.1)
				(type default)
			)
			(layer "F.Fab")
		)
		(fp_line
			(start 0.12065 -0.2794)
			(end 0.12065 -0.3048)
			(stroke
				(width 0.1)
				(type default)
			)
			(layer "F.Fab")
		)
		(fp_line
			(start -0.12065 -0.2794)
			(end 0.12065 -0.2794)
			(stroke
				(width 0.1)
				(type default)
			)
			(layer "F.Fab")
		)
		(fp_line
			(start 0.120396 0.2794)
			(end -0.12065 0.2794)
			(stroke
				(width 0.1)
				(type default)
			)
			(layer "F.Fab")
		)
		(fp_line
			(start -0.12065 0.2794)
			(end -0.12065 0.3048)
			(stroke
				(width 0.1)
				(type default)
			)
			(layer "F.Fab")
		)
		(fp_line
			(start 0.67945 0.3048)
			(end 0.120396 0.3048)
			(stroke
				(width 0.1)
				(type default)
			)
			(layer "F.Fab")
		)
		(fp_line
			(start 0.120396 0.3048)
			(end 0.120396 0.2794)
			(stroke
				(width 0.1)
				(type default)
			)
			(layer "F.Fab")
		)
		(fp_line
			(start -0.12065 0.3048)
			(end -0.67945 0.3048)
			(stroke
				(width 0.1)
				(type default)
			)
			(layer "F.Fab")
		)
		(fp_line
			(start -0.67945 0.3048)
			(end -0.67945 -0.305054)
			(stroke
				(width 0.1)
				(type default)
			)
			(layer "F.Fab")
		)
		(pad "1" smd circle
			(at -0.40005 0 90)
			(size 0 0)
			(layers "F.Cu" "F.Mask" "F.Paste")
			(net "PVCCIN_CPU1")
		)
		(pad "2" smd circle
			(at 0.40005 0 90)
			(size 0 0)
			(layers "F.Cu" "F.Mask" "F.Paste")
			(net "GND")
		)
	)
	(footprint ""
		(layer "F.Cu")
		(at 435.588664 -128.877314)
		(property "Reference" "PJ54"
			(at 0.826516 -1.260856 0)
			(unlocked yes)
			(layer "F.SilkS")
			(effects
				(font
					(size 0.7874 0.5842)
					(thickness 0.1524)
				)
				(justify left)
			)
		)
		(property "Value" ""
			(at 0 0 0)
			(layer "F.Fab")
			(effects
				(font
					(size 1.27 1.27)
				)
			)
		)
		(duplicate_pad_numbers_are_jumpers no)
		(pad "1" smd circle
			(at -0.7493 0 90)
			(size 0 0)
			(layers "F.Cu" "F.Mask" "F.Paste")
			(net "VSENSE_PVCCD_HV_CPU0_DP")
		)
		(pad "2" smd rect
			(at 0.7493 0 270)
			(size 0.7112 0.8128)
			(layers "F.Cu" "F.Mask" "F.Paste")
			(net "SH_PVCCD_HV_CPU0")
		)
		(zone
			(layer "F.Cu")
			(hatch none 0.5)
			(connect_pads
				(clearance 0)
			)
			(min_thickness 0.25)
			(keepout
				(tracks allowed)
				(vias not_allowed)
				(pads allowed)
				(copperpour not_allowed)
				(footprints allowed)
			)
			(placement
				(enabled no)
				(sheetname "")
			)
			(fill
				(thermal_gap 0.5)
				(thermal_bridge_width 0.5)
				(island_removal_mode 0)
			)
			(polygon
				(pts
					(xy 434.407564 -128.466088) (xy 436.795164 -128.466088) (xy 436.795164 -129.283714) (xy 434.407564 -129.283714)
				)
			)
		)
	)
	(footprint ""
		(layer "F.Cu")
		(at 378.43841 -402.371052 -90)
		(property "Reference" "C938"
			(at 0 0 270)
			(layer "F.SilkS")
			(hide yes)
			(effects
				(font
					(size 1.27 1.27)
				)
			)
		)
		(property "Value" ""
			(at 0 0 270)
			(layer "F.Fab")
			(effects
				(font
					(size 1.27 1.27)
				)
			)
		)
		(duplicate_pad_numbers_are_jumpers no)
		(fp_line
			(start -0.299974 0.150114)
			(end -0.299974 -0.150114)
			(stroke
				(width 0.1)
				(type default)
			)
			(layer "F.Fab")
		)
		(fp_line
			(start 0.299974 0.150114)
			(end -0.299974 0.150114)
			(stroke
				(width 0.1)
				(type default)
			)
			(layer "F.Fab")
		)
		(fp_line
			(start -0.299974 -0.150114)
			(end 0.299974 -0.150114)
			(stroke
				(width 0.1)
				(type default)
			)
			(layer "F.Fab")
		)
		(fp_line
			(start 0.299974 -0.150114)
			(end 0.299974 0.150114)
			(stroke
				(width 0.1)
				(type default)
			)
			(layer "F.Fab")
		)
		(pad "1" smd rect
			(at -0.2667 0 270)
			(size 0.3048 0.381)
			(layers "F.Cu" "F.Mask" "F.Paste")
			(net "P5E_CPU0_PE2_TX_C_DN<13>")
		)
		(pad "2" smd rect
			(at 0.2667 0 270)
			(size 0.3048 0.381)
			(layers "F.Cu" "F.Mask" "F.Paste")
			(net "P5E_CPU0_PE2_TX_DN<13>")
		)
	)
	(footprint ""
		(layer "F.Cu")
		(at 117.526816 -241.97691 -90)
		(property "Reference" "C290"
			(at 0 0 270)
			(layer "F.SilkS")
			(hide yes)
			(effects
				(font
					(size 1.27 1.27)
				)
			)
		)
		(property "Value" ""
			(at 0 0 270)
			(layer "F.Fab")
			(effects
				(font
					(size 1.27 1.27)
				)
			)
		)
		(duplicate_pad_numbers_are_jumpers no)
		(fp_line
			(start -0.7874 0.4064)
			(end -0.7874 -0.4064)
			(stroke
				(width 0.1524)
				(type default)
			)
			(layer "F.SilkS")
		)
		(fp_line
			(start 0.7874 0.4064)
			(end -0.7874 0.4064)
			(stroke
				(width 0.1524)
				(type default)
			)
			(layer "F.SilkS")
		)
		(fp_line
			(start -0.7874 -0.4064)
			(end 0.7874 -0.4064)
			(stroke
				(width 0.1524)
				(type default)
			)
			(layer "F.SilkS")
		)
		(fp_line
			(start 0.7874 -0.4064)
			(end 0.7874 0.4064)
			(stroke
				(width 0.1524)
				(type default)
			)
			(layer "F.SilkS")
		)
		(fp_line
			(start -0.67945 0.3048)
			(end -0.67945 -0.305054)
			(stroke
				(width 0.1)
				(type default)
			)
			(layer "F.Fab")
		)
		(fp_line
			(start -0.12065 0.3048)
			(end -0.67945 0.3048)
			(stroke
				(width 0.1)
				(type default)
			)
			(layer "F.Fab")
		)
		(fp_line
			(start 0.120396 0.3048)
			(end 0.120396 0.2794)
			(stroke
				(width 0.1)
				(type default)
			)
			(layer "F.Fab")
		)
		(fp_line
			(start 0.67945 0.3048)
			(end 0.120396 0.3048)
			(stroke
				(width 0.1)
				(type default)
			)
			(layer "F.Fab")
		)
		(fp_line
			(start -0.12065 0.2794)
			(end -0.12065 0.3048)
			(stroke
				(width 0.1)
				(type default)
			)
			(layer "F.Fab")
		)
		(fp_line
			(start 0.120396 0.2794)
			(end -0.12065 0.2794)
			(stroke
				(width 0.1)
				(type default)
			)
			(layer "F.Fab")
		)
		(fp_line
			(start -0.12065 -0.2794)
			(end 0.12065 -0.2794)
			(stroke
				(width 0.1)
				(type default)
			)
			(layer "F.Fab")
		)
		(fp_line
			(start 0.12065 -0.2794)
			(end 0.12065 -0.3048)
			(stroke
				(width 0.1)
				(type default)
			)
			(layer "F.Fab")
		)
		(fp_line
			(start 0.12065 -0.3048)
			(end 0.67945 -0.3048)
			(stroke
				(width 0.1)
				(type default)
			)
			(layer "F.Fab")
		)
		(fp_line
			(start 0.67945 -0.3048)
			(end 0.67945 0.3048)
			(stroke
				(width 0.1)
				(type default)
			)
			(layer "F.Fab")
		)
		(fp_line
			(start -0.67945 -0.305054)
			(end -0.12065 -0.305054)
			(stroke
				(width 0.1)
				(type default)
			)
			(layer "F.Fab")
		)
		(fp_line
			(start -0.12065 -0.305054)
			(end -0.12065 -0.2794)
			(stroke
				(width 0.1)
				(type default)
			)
			(layer "F.Fab")
		)
		(pad "1" smd circle
			(at -0.40005 0 270)
			(size 0 0)
			(layers "F.Cu" "F.Mask" "F.Paste")
			(net "PVCCIN_CPU1")
		)
		(pad "2" smd circle
			(at 0.40005 0 270)
			(size 0 0)
			(layers "F.Cu" "F.Mask" "F.Paste")
			(net "GND")
		)
	)
	(footprint ""
		(layer "F.Cu")
		(at 125.124972 -139.178538)
		(property "Reference" "C174"
			(at 0 0 0)
			(layer "F.SilkS")
			(hide yes)
			(effects
				(font
					(size 1.27 1.27)
				)
			)
		)
		(property "Value" ""
			(at 0 0 0)
			(layer "F.Fab")
			(effects
				(font
					(size 1.27 1.27)
				)
			)
		)
		(duplicate_pad_numbers_are_jumpers no)
		(fp_line
			(start -0.7874 -0.4064)
			(end 0.7874 -0.4064)
			(stroke
				(width 0.1524)
				(type default)
			)
			(layer "F.SilkS")
		)
		(fp_line
			(start -0.7874 0.4064)
			(end -0.7874 -0.4064)
			(stroke
				(width 0.1524)
				(type default)
			)
			(layer "F.SilkS")
		)
		(fp_line
			(start 0.7874 -0.4064)
			(end 0.7874 0.4064)
			(stroke
				(width 0.1524)
				(type default)
			)
			(layer "F.SilkS")
		)
		(fp_line
			(start 0.7874 0.4064)
			(end -0.7874 0.4064)
			(stroke
				(width 0.1524)
				(type default)
			)
			(layer "F.SilkS")
		)
		(fp_line
			(start -0.67945 -0.305054)
			(end -0.12065 -0.305054)
			(stroke
				(width 0.1)
				(type default)
			)
			(layer "F.Fab")
		)
		(fp_line
			(start -0.67945 0.3048)
			(end -0.67945 -0.305054)
			(stroke
				(width 0.1)
				(type default)
			)
			(layer "F.Fab")
		)
		(fp_line
			(start -0.12065 -0.305054)
			(end -0.12065 -0.2794)
			(stroke
				(width 0.1)
				(type default)
			)
			(layer "F.Fab")
		)
		(fp_line
			(start -0.12065 -0.2794)
			(end 0.12065 -0.2794)
			(stroke
				(width 0.1)
				(type default)
			)
			(layer "F.Fab")
		)
		(fp_line
			(start -0.12065 0.2794)
			(end -0.12065 0.3048)
			(stroke
				(width 0.1)
				(type default)
			)
			(layer "F.Fab")
		)
		(fp_line
			(start -0.12065 0.3048)
			(end -0.67945 0.3048)
			(stroke
				(width 0.1)
				(type default)
			)
			(layer "F.Fab")
		)
		(fp_line
			(start 0.120396 0.2794)
			(end -0.12065 0.2794)
			(stroke
				(width 0.1)
				(type default)
			)
			(layer "F.Fab")
		)
		(fp_line
			(start 0.120396 0.3048)
			(end 0.120396 0.2794)
			(stroke
				(width 0.1)
				(type default)
			)
			(layer "F.Fab")
		)
		(fp_line
			(start 0.12065 -0.3048)
			(end 0.67945 -0.3048)
			(stroke
				(width 0.1)
				(type default)
			)
			(layer "F.Fab")
		)
		(fp_line
			(start 0.12065 -0.2794)
			(end 0.12065 -0.3048)
			(stroke
				(width 0.1)
				(type default)
			)
			(layer "F.Fab")
		)
		(fp_line
			(start 0.67945 -0.3048)
			(end 0.67945 0.3048)
			(stroke
				(width 0.1)
				(type default)
			)
			(layer "F.Fab")
		)
		(fp_line
			(start 0.67945 0.3048)
			(end 0.120396 0.3048)
			(stroke
				(width 0.1)
				(type default)
			)
			(layer "F.Fab")
		)
		(pad "1" smd circle
			(at -0.40005 0)
			(size 0 0)
			(layers "F.Cu" "F.Mask" "F.Paste")
			(net "P3V3_AUX")
		)
		(pad "2" smd circle
			(at 0.40005 0)
			(size 0 0)
			(layers "F.Cu" "F.Mask" "F.Paste")
			(net "GND")
		)
	)
	(footprint ""
		(layer "F.Cu")
		(at 357.487982 -385.17449 180)
		(property "Reference" "C2271"
			(at 0 0 180)
			(layer "F.SilkS")
			(hide yes)
			(effects
				(font
					(size 1.27 1.27)
				)
			)
		)
		(property "Value" ""
			(at 0 0 180)
			(layer "F.Fab")
			(effects
				(font
					(size 1.27 1.27)
				)
			)
		)
		(duplicate_pad_numbers_are_jumpers no)
		(fp_line
			(start 0.7874 0.4064)
			(end -0.7874 0.4064)
			(stroke
				(width 0.1524)
				(type default)
			)
			(layer "F.SilkS")
		)
		(fp_line
			(start 0.7874 -0.4064)
			(end 0.7874 0.4064)
			(stroke
				(width 0.1524)
				(type default)
			)
			(layer "F.SilkS")
		)
		(fp_line
			(start -0.7874 0.4064)
			(end -0.7874 -0.4064)
			(stroke
				(width 0.1524)
				(type default)
			)
			(layer "F.SilkS")
		)
		(fp_line
			(start -0.7874 -0.4064)
			(end 0.7874 -0.4064)
			(stroke
				(width 0.1524)
				(type default)
			)
			(layer "F.SilkS")
		)
		(fp_line
			(start 0.67945 0.3048)
			(end 0.120396 0.3048)
			(stroke
				(width 0.1)
				(type default)
			)
			(layer "F.Fab")
		)
		(fp_line
			(start 0.67945 -0.3048)
			(end 0.67945 0.3048)
			(stroke
				(width 0.1)
				(type default)
			)
			(layer "F.Fab")
		)
		(fp_line
			(start 0.12065 -0.2794)
			(end 0.12065 -0.3048)
			(stroke
				(width 0.1)
				(type default)
			)
			(layer "F.Fab")
		)
		(fp_line
			(start 0.12065 -0.3048)
			(end 0.67945 -0.3048)
			(stroke
				(width 0.1)
				(type default)
			)
			(layer "F.Fab")
		)
		(fp_line
			(start 0.120396 0.3048)
			(end 0.120396 0.2794)
			(stroke
				(width 0.1)
				(type default)
			)
			(layer "F.Fab")
		)
		(fp_line
			(start 0.120396 0.2794)
			(end -0.12065 0.2794)
			(stroke
				(width 0.1)
				(type default)
			)
			(layer "F.Fab")
		)
		(fp_line
			(start -0.12065 0.3048)
			(end -0.67945 0.3048)
			(stroke
				(width 0.1)
				(type default)
			)
			(layer "F.Fab")
		)
		(fp_line
			(start -0.12065 0.2794)
			(end -0.12065 0.3048)
			(stroke
				(width 0.1)
				(type default)
			)
			(layer "F.Fab")
		)
		(fp_line
			(start -0.12065 -0.2794)
			(end 0.12065 -0.2794)
			(stroke
				(width 0.1)
				(type default)
			)
			(layer "F.Fab")
		)
		(fp_line
			(start -0.12065 -0.305054)
			(end -0.12065 -0.2794)
			(stroke
				(width 0.1)
				(type default)
			)
			(layer "F.Fab")
		)
		(fp_line
			(start -0.67945 0.3048)
			(end -0.67945 -0.305054)
			(stroke
				(width 0.1)
				(type default)
			)
			(layer "F.Fab")
		)
		(fp_line
			(start -0.67945 -0.305054)
			(end -0.12065 -0.305054)
			(stroke
				(width 0.1)
				(type default)
			)
			(layer "F.Fab")
		)
		(pad "1" smd circle
			(at -0.40005 0 180)
			(size 0 0)
			(layers "F.Cu" "F.Mask" "F.Paste")
			(net "GPU_3V3IO_RSVD1_ISO")
		)
		(pad "2" smd circle
			(at 0.40005 0 180)
			(size 0 0)
			(layers "F.Cu" "F.Mask" "F.Paste")
			(net "GND")
		)
	)
)
